# S9S_MB_2U (Grand Teton) — schematic netlist excerpt (pin names and nets, part order shuffled) for the footprints in the layout excerpt that follows; sources: Cadence DE-HDL packaged netlist, KiCad conversion of 03242023_DA0F0TMBIJ0_F0T_Motherboard_J_brd_V01_OCP.brd

R3956  Q_RES  0 5% CHIP  pkg 0402LF  page 193 : A = P12V_E1S_IMON_0 ; B = P12V_E1S_0_ISENSE_MPS_TIC
R2313  Q_RES  0 5% CHIP  pkg 0402LF  page 236 : A = RST_SMB_SWITCH_N ; B = RST_SMB_S3M_N

(kicad_pcb
	(version 20260206)
	(generator "pcbnew")
	(generator_version "10.0")
	(general
		(thickness 1.6)
		(legacy_teardrops no)
	)
	(paper "A4")
	(title_block
		(title "03242023_DA0F0TMBIJ0_F0T_Motherboard_J_brd_V01_OCP.brd")
		(comment 1 "Grand Teton / footprints 1212-1213 of 6105")
	)
	(layers
		(0 "F.Cu" signal "TOP")
		(4 "In1.Cu" signal "GND")
		(6 "In2.Cu" signal "IN1")
		(8 "In3.Cu" signal "GND1")
		(10 "In4.Cu" signal "IN2")
		(12 "In5.Cu" signal "GND2")
		(14 "In6.Cu" signal "IN3")
		(16 "In7.Cu" signal "GND3")
		(18 "In8.Cu" signal "VCC")
		(20 "In9.Cu" signal "VCC1")
		(22 "In10.Cu" signal "GND4")
		(24 "In11.Cu" signal "IN4")
		(26 "In12.Cu" signal "GND5")
		(28 "In13.Cu" signal "IN5")
		(30 "In14.Cu" signal "GND6")
		(32 "In15.Cu" signal "IN6")
		(34 "In16.Cu" signal "GND7")
		(2 "B.Cu" signal "BOTTOM")
		(9 "F.Adhes" user "F.Adhesive")
		(11 "B.Adhes" user "B.Adhesive")
		(13 "F.Paste" user "Package Geometry/Pastemask Top")
		(15 "B.Paste" user "Package Geometry/Pastemask Bottom")
		(5 "F.SilkS" user "Ref Des/Silkscreen Top")
		(7 "B.SilkS" user "Ref Des/Silkscreen Bottom")
		(1 "F.Mask" user "Board Geometry/Soldermask Top")
		(3 "B.Mask" user "Board Geometry/Soldermask Bottom")
		(17 "Dwgs.User" user "User.Drawings")
		(19 "Cmts.User" user "User.Comments")
		(21 "Eco1.User" user "User.Eco1")
		(23 "Eco2.User" user "User.Eco2")
		(25 "Edge.Cuts" user "Board Geometry/Outline")
		(27 "Margin" user)
		(31 "F.CrtYd" user "Package Geometry/Place Bound Top")
		(29 "B.CrtYd" user "Package Geometry/Place Bound Bottom")
		(35 "F.Fab" user "Ref Des/Assembly Top")
		(33 "B.Fab" user "Ref Des/Assembly Bottom")
	)
	(footprint ""
		(layer "F.Cu")
		(at 257.85953 -55.479442)
		(property "Reference" "R3956"
			(at 0 0 0)
			(layer "F.SilkS")
			(hide yes)
			(effects
				(font
					(size 1.27 1.27)
				)
			)
		)
		(property "Value" ""
			(at 0 0 0)
			(layer "F.Fab")
			(effects
				(font
					(size 1.27 1.27)
				)
			)
		)
		(duplicate_pad_numbers_are_jumpers no)
		(fp_line
			(start -0.7874 -0.4064)
			(end 0.7874 -0.4064)
			(stroke
				(width 0.1524)
				(type default)
			)
			(layer "F.SilkS")
		)
		(fp_line
			(start -0.7874 0.4064)
			(end -0.7874 -0.4064)
			(stroke
				(width 0.1524)
				(type default)
			)
			(layer "F.SilkS")
		)
		(fp_line
			(start 0.7874 -0.4064)
			(end 0.7874 0.4064)
			(stroke
				(width 0.1524)
				(type default)
			)
			(layer "F.SilkS")
		)
		(fp_line
			(start 0.7874 0.4064)
			(end -0.7874 0.4064)
			(stroke
				(width 0.1524)
				(type default)
			)
			(layer "F.SilkS")
		)
		(fp_line
			(start -0.67945 -0.305054)
			(end -0.12065 -0.305054)
			(stroke
				(width 0.1)
				(type default)
			)
			(layer "F.Fab")
		)
		(fp_line
			(start -0.67945 0.3048)
			(end -0.67945 -0.305054)
			(stroke
				(width 0.1)
				(type default)
			)
			(layer "F.Fab")
		)
		(fp_line
			(start -0.12065 -0.305054)
			(end -0.12065 -0.2794)
			(stroke
				(width 0.1)
				(type default)
			)
			(layer "F.Fab")
		)
		(fp_line
			(start -0.12065 -0.2794)
			(end 0.12065 -0.2794)
			(stroke
				(width 0.1)
				(type default)
			)
			(layer "F.Fab")
		)
		(fp_line
			(start -0.12065 0.2794)
			(end -0.12065 0.3048)
			(stroke
				(width 0.1)
				(type default)
			)
			(layer "F.Fab")
		)
		(fp_line
			(start -0.12065 0.3048)
			(end -0.67945 0.3048)
			(stroke
				(width 0.1)
				(type default)
			)
			(layer "F.Fab")
		)
		(fp_line
			(start 0.120396 0.2794)
			(end -0.12065 0.2794)
			(stroke
				(width 0.1)
				(type default)
			)
			(layer "F.Fab")
		)
		(fp_line
			(start 0.120396 0.3048)
			(end 0.120396 0.2794)
			(stroke
				(width 0.1)
				(type default)
			)
			(layer "F.Fab")
		)
		(fp_line
			(start 0.12065 -0.3048)
			(end 0.67945 -0.3048)
			(stroke
				(width 0.1)
				(type default)
			)
			(layer "F.Fab")
		)
		(fp_line
			(start 0.12065 -0.2794)
			(end 0.12065 -0.3048)
			(stroke
				(width 0.1)
				(type default)
			)
			(layer "F.Fab")
		)
		(fp_line
			(start 0.67945 -0.3048)
			(end 0.67945 0.3048)
			(stroke
				(width 0.1)
				(type default)
			)
			(layer "F.Fab")
		)
		(fp_line
			(start 0.67945 0.3048)
			(end 0.120396 0.3048)
			(stroke
				(width 0.1)
				(type default)
			)
			(layer "F.Fab")
		)
		(pad "1" smd circle
			(at -0.40005 0)
			(size 0 0)
			(layers "F.Cu" "F.Mask" "F.Paste")
			(net "P12V_E1S_IMON_0")
		)
		(pad "2" smd circle
			(at 0.40005 0)
			(size 0 0)
			(layers "F.Cu" "F.Mask" "F.Paste")
			(net "P12V_E1S_0_ISENSE_MPS_TIC")
		)
	)
	(footprint ""
		(layer "F.Cu")
		(at 162.34283 -73.727818 180)
		(property "Reference" "R2313"
			(at 0 0 180)
			(layer "F.SilkS")
			(hide yes)
			(effects
				(font
					(size 1.27 1.27)
				)
			)
		)
		(property "Value" ""
			(at 0 0 180)
			(layer "F.Fab")
			(effects
				(font
					(size 1.27 1.27)
				)
			)
		)
		(duplicate_pad_numbers_are_jumpers no)
		(fp_line
			(start 0.7874 0.4064)
			(end -0.7874 0.4064)
			(stroke
				(width 0.1524)
				(type default)
			)
			(layer "F.SilkS")
		)
		(fp_line
			(start 0.7874 -0.4064)
			(end 0.7874 0.4064)
			(stroke
				(width 0.1524)
				(type default)
			)
			(layer "F.SilkS")
		)
		(fp_line
			(start -0.7874 0.4064)
			(end -0.7874 -0.4064)
			(stroke
				(width 0.1524)
				(type default)
			)
			(layer "F.SilkS")
		)
		(fp_line
			(start -0.7874 -0.4064)
			(end 0.7874 -0.4064)
			(stroke
				(width 0.1524)
				(type default)
			)
			(layer "F.SilkS")
		)
		(fp_line
			(start 0.67945 0.3048)
			(end 0.120396 0.3048)
			(stroke
				(width 0.1)
				(type default)
			)
			(layer "F.Fab")
		)
		(fp_line
			(start 0.67945 -0.3048)
			(end 0.67945 0.3048)
			(stroke
				(width 0.1)
				(type default)
			)
			(layer "F.Fab")
		)
		(fp_line
			(start 0.12065 -0.2794)
			(end 0.12065 -0.3048)
			(stroke
				(width 0.1)
				(type default)
			)
			(layer "F.Fab")
		)
		(fp_line
			(start 0.12065 -0.3048)
			(end 0.67945 -0.3048)
			(stroke
				(width 0.1)
				(type default)
			)
			(layer "F.Fab")
		)
		(fp_line
			(start 0.120396 0.3048)
			(end 0.120396 0.2794)
			(stroke
				(width 0.1)
				(type default)
			)
			(layer "F.Fab")
		)
		(fp_line
			(start 0.120396 0.2794)
			(end -0.12065 0.2794)
			(stroke
				(width 0.1)
				(type default)
			)
			(layer "F.Fab")
		)
		(fp_line
			(start -0.12065 0.3048)
			(end -0.67945 0.3048)
			(stroke
				(width 0.1)
				(type default)
			)
			(layer "F.Fab")
		)
		(fp_line
			(start -0.12065 0.2794)
			(end -0.12065 0.3048)
			(stroke
				(width 0.1)
				(type default)
			)
			(layer "F.Fab")
		)
		(fp_line
			(start -0.12065 -0.2794)
			(end 0.12065 -0.2794)
			(stroke
				(width 0.1)
				(type default)
			)
			(layer "F.Fab")
		)
		(fp_line
			(start -0.12065 -0.305054)
			(end -0.12065 -0.2794)
			(stroke
				(width 0.1)
				(type default)
			)
			(layer "F.Fab")
		)
		(fp_line
			(start -0.67945 0.3048)
			(end -0.67945 -0.305054)
			(stroke
				(width 0.1)
				(type default)
			)
			(layer "F.Fab")
		)
		(fp_line
			(start -0.67945 -0.305054)
			(end -0.12065 -0.305054)
			(stroke
				(width 0.1)
				(type default)
			)
			(layer "F.Fab")
		)
		(pad "1" smd circle
			(at -0.40005 0 180)
			(size 0 0)
			(layers "F.Cu" "F.Mask" "F.Paste")
			(net "RST_SMB_SWITCH_N")
		)
		(pad "2" smd circle
			(at 0.40005 0 180)
			(size 0 0)
			(layers "F.Cu" "F.Mask" "F.Paste")
			(net "RST_SMB_S3M_N")
		)
	)
)
